(kicad_pcb
	(version 20260206)
	(generator "pcbnew")
	(generator_version "10.0")
	(general
		(thickness 1.6)
		(legacy_teardrops no)
	)
	(paper "A4")
	(title_block
		(title "03242023_DA0F0TMBIJ0_F0T_Motherboard_J_brd_V01_OCP.brd")
		(comment 1 "Grand Teton / footprints 5246-5251 of 6105")
	)
	(layers
		(0 "F.Cu" signal "TOP")
		(4 "In1.Cu" signal "GND")
		(6 "In2.Cu" signal "IN1")
		(8 "In3.Cu" signal "GND1")
		(10 "In4.Cu" signal "IN2")
		(12 "In5.Cu" signal "GND2")
		(14 "In6.Cu" signal "IN3")
		(16 "In7.Cu" signal "GND3")
		(18 "In8.Cu" signal "VCC")
		(20 "In9.Cu" signal "VCC1")
		(22 "In10.Cu" signal "GND4")
		(24 "In11.Cu" signal "IN4")
		(26 "In12.Cu" signal "GND5")
		(28 "In13.Cu" signal "IN5")
		(30 "In14.Cu" signal "GND6")
		(32 "In15.Cu" signal "IN6")
		(34 "In16.Cu" signal "GND7")
		(2 "B.Cu" signal "BOTTOM")
		(9 "F.Adhes" user "F.Adhesive")
		(11 "B.Adhes" user "B.Adhesive")
		(13 "F.Paste" user "Package Geometry/Pastemask Top")
		(15 "B.Paste" user "Package Geometry/Pastemask Bottom")
		(5 "F.SilkS" user "Ref Des/Silkscreen Top")
		(7 "B.SilkS" user "Ref Des/Silkscreen Bottom")
		(1 "F.Mask" user "Board Geometry/Soldermask Top")
		(3 "B.Mask" user "Board Geometry/Soldermask Bottom")
		(17 "Dwgs.User" user "User.Drawings")
		(19 "Cmts.User" user "User.Comments")
		(21 "Eco1.User" user "User.Eco1")
		(23 "Eco2.User" user "User.Eco2")
		(25 "Edge.Cuts" user "Board Geometry/Outline")
		(27 "Margin" user)
		(31 "F.CrtYd" user "Package Geometry/Place Bound Top")
		(29 "B.CrtYd" user "Package Geometry/Place Bound Bottom")
		(35 "F.Fab" user "Ref Des/Assembly Top")
		(33 "B.Fab" user "Ref Des/Assembly Bottom")
	)
	(footprint ""
		(layer "B.Cu")
		(at 156.580078 -102.661466)
		(property "Reference" "R122"
			(at 0 0 0)
			(layer "B.SilkS")
			(hide yes)
			(effects
				(font
					(size 1.27 1.27)
				)
				(justify mirror)
			)
		)
		(property "Value" ""
			(at 0 0 0)
			(layer "B.Fab")
			(effects
				(font
					(size 1.27 1.27)
				)
				(justify mirror)
			)
		)
		(duplicate_pad_numbers_are_jumpers no)
		(fp_line
			(start -0.7874 -0.4064)
			(end -0.7874 0.4064)
			(stroke
				(width 0.1524)
				(type default)
			)
			(layer "B.SilkS")
		)
		(fp_line
			(start -0.7874 0.4064)
			(end 0.7874 0.4064)
			(stroke
				(width 0.1524)
				(type default)
			)
			(layer "B.SilkS")
		)
		(fp_line
			(start 0.7874 -0.4064)
			(end -0.7874 -0.4064)
			(stroke
				(width 0.1524)
				(type default)
			)
			(layer "B.SilkS")
		)
		(fp_line
			(start 0.7874 0.4064)
			(end 0.7874 -0.4064)
			(stroke
				(width 0.1524)
				(type default)
			)
			(layer "B.SilkS")
		)
		(fp_line
			(start -0.67945 -0.3048)
			(end -0.67945 0.3048)
			(stroke
				(width 0.1)
				(type default)
			)
			(layer "B.Fab")
		)
		(fp_line
			(start -0.67945 0.3048)
			(end -0.120396 0.3048)
			(stroke
				(width 0.1)
				(type default)
			)
			(layer "B.Fab")
		)
		(fp_line
			(start -0.12065 -0.3048)
			(end -0.67945 -0.3048)
			(stroke
				(width 0.1)
				(type default)
			)
			(layer "B.Fab")
		)
		(fp_line
			(start -0.12065 -0.2794)
			(end -0.12065 -0.3048)
			(stroke
				(width 0.1)
				(type default)
			)
			(layer "B.Fab")
		)
		(fp_line
			(start -0.120396 0.2794)
			(end 0.12065 0.2794)
			(stroke
				(width 0.1)
				(type default)
			)
			(layer "B.Fab")
		)
		(fp_line
			(start -0.120396 0.3048)
			(end -0.120396 0.2794)
			(stroke
				(width 0.1)
				(type default)
			)
			(layer "B.Fab")
		)
		(fp_line
			(start 0.12065 -0.305054)
			(end 0.12065 -0.2794)
			(stroke
				(width 0.1)
				(type default)
			)
			(layer "B.Fab")
		)
		(fp_line
			(start 0.12065 -0.2794)
			(end -0.12065 -0.2794)
			(stroke
				(width 0.1)
				(type default)
			)
			(layer "B.Fab")
		)
		(fp_line
			(start 0.12065 0.2794)
			(end 0.12065 0.3048)
			(stroke
				(width 0.1)
				(type default)
			)
			(layer "B.Fab")
		)
		(fp_line
			(start 0.12065 0.3048)
			(end 0.67945 0.3048)
			(stroke
				(width 0.1)
				(type default)
			)
			(layer "B.Fab")
		)
		(fp_line
			(start 0.67945 -0.305054)
			(end 0.12065 -0.305054)
			(stroke
				(width 0.1)
				(type default)
			)
			(layer "B.Fab")
		)
		(fp_line
			(start 0.67945 0.3048)
			(end 0.67945 -0.305054)
			(stroke
				(width 0.1)
				(type default)
			)
			(layer "B.Fab")
		)
		(pad "1" smd circle
			(at 0.40005 0 180)
			(size 0 0)
			(layers "B.Cu" "B.Mask" "B.Paste")
			(net "PWRGD_DRAMPWRGD_CPU1_AB_R_LVC1")
		)
		(pad "2" smd circle
			(at -0.40005 0 180)
			(size 0 0)
			(layers "B.Cu" "B.Mask" "B.Paste")
			(net "PWRGD_DRAMPWRGD_CPU1_AB_LVC1_R2")
		)
	)
	(footprint ""
		(layer "B.Cu")
		(at 461.35544 -314.772294 90)
		(property "Reference" "R3889"
			(at 0 0 90)
			(layer "B.SilkS")
			(hide yes)
			(effects
				(font
					(size 1.27 1.27)
				)
				(justify mirror)
			)
		)
		(property "Value" ""
			(at 0 0 90)
			(layer "B.Fab")
			(effects
				(font
					(size 1.27 1.27)
				)
				(justify mirror)
			)
		)
		(duplicate_pad_numbers_are_jumpers no)
		(fp_line
			(start 0.7874 -0.4064)
			(end -0.7874 -0.4064)
			(stroke
				(width 0.1524)
				(type default)
			)
			(layer "B.SilkS")
		)
		(fp_line
			(start -0.7874 -0.4064)
			(end -0.7874 0.4064)
			(stroke
				(width 0.1524)
				(type default)
			)
			(layer "B.SilkS")
		)
		(fp_line
			(start 0.7874 0.4064)
			(end 0.7874 -0.4064)
			(stroke
				(width 0.1524)
				(type default)
			)
			(layer "B.SilkS")
		)
		(fp_line
			(start -0.7874 0.4064)
			(end 0.7874 0.4064)
			(stroke
				(width 0.1524)
				(type default)
			)
			(layer "B.SilkS")
		)
		(fp_line
			(start 0.67945 -0.305054)
			(end 0.12065 -0.305054)
			(stroke
				(width 0.1)
				(type default)
			)
			(layer "B.Fab")
		)
		(fp_line
			(start 0.12065 -0.305054)
			(end 0.12065 -0.2794)
			(stroke
				(width 0.1)
				(type default)
			)
			(layer "B.Fab")
		)
		(fp_line
			(start -0.12065 -0.3048)
			(end -0.67945 -0.3048)
			(stroke
				(width 0.1)
				(type default)
			)
			(layer "B.Fab")
		)
		(fp_line
			(start -0.67945 -0.3048)
			(end -0.67945 0.3048)
			(stroke
				(width 0.1)
				(type default)
			)
			(layer "B.Fab")
		)
		(fp_line
			(start 0.12065 -0.2794)
			(end -0.12065 -0.2794)
			(stroke
				(width 0.1)
				(type default)
			)
			(layer "B.Fab")
		)
		(fp_line
			(start -0.12065 -0.2794)
			(end -0.12065 -0.3048)
			(stroke
				(width 0.1)
				(type default)
			)
			(layer "B.Fab")
		)
		(fp_line
			(start 0.12065 0.2794)
			(end 0.12065 0.3048)
			(stroke
				(width 0.1)
				(type default)
			)
			(layer "B.Fab")
		)
		(fp_line
			(start -0.120396 0.2794)
			(end 0.12065 0.2794)
			(stroke
				(width 0.1)
				(type default)
			)
			(layer "B.Fab")
		)
		(fp_line
			(start 0.67945 0.3048)
			(end 0.67945 -0.305054)
			(stroke
				(width 0.1)
				(type default)
			)
			(layer "B.Fab")
		)
		(fp_line
			(start 0.12065 0.3048)
			(end 0.67945 0.3048)
			(stroke
				(width 0.1)
				(type default)
			)
			(layer "B.Fab")
		)
		(fp_line
			(start -0.120396 0.3048)
			(end -0.120396 0.2794)
			(stroke
				(width 0.1)
				(type default)
			)
			(layer "B.Fab")
		)
		(fp_line
			(start -0.67945 0.3048)
			(end -0.120396 0.3048)
			(stroke
				(width 0.1)
				(type default)
			)
			(layer "B.Fab")
		)
		(pad "1" smd circle
			(at 0.40005 0 270)
			(size 0 0)
			(layers "B.Cu" "B.Mask" "B.Paste")
			(net "I3C_SPD_DDREFGH_CPU0_LVC1_SCL_6")
		)
		(pad "2" smd circle
			(at -0.40005 0 270)
			(size 0 0)
			(layers "B.Cu" "B.Mask" "B.Paste")
			(net "I3C_SPD_DDREFGH_CPU0_LVC1_SCL")
		)
	)
	(footprint ""
		(layer "B.Cu")
		(at 309.25389 -30.734508)
		(property "Reference" "R378"
			(at 0 0 0)
			(layer "B.SilkS")
			(hide yes)
			(effects
				(font
					(size 1.27 1.27)
				)
				(justify mirror)
			)
		)
		(property "Value" ""
			(at 0 0 0)
			(layer "B.Fab")
			(effects
				(font
					(size 1.27 1.27)
				)
				(justify mirror)
			)
		)
		(duplicate_pad_numbers_are_jumpers no)
		(fp_line
			(start -0.7874 -0.4064)
			(end -0.7874 0.4064)
			(stroke
				(width 0.1524)
				(type default)
			)
			(layer "B.SilkS")
		)
		(fp_line
			(start -0.7874 0.4064)
			(end 0.7874 0.4064)
			(stroke
				(width 0.1524)
				(type default)
			)
			(layer "B.SilkS")
		)
		(fp_line
			(start 0.7874 -0.4064)
			(end -0.7874 -0.4064)
			(stroke
				(width 0.1524)
				(type default)
			)
			(layer "B.SilkS")
		)
		(fp_line
			(start 0.7874 0.4064)
			(end 0.7874 -0.4064)
			(stroke
				(width 0.1524)
				(type default)
			)
			(layer "B.SilkS")
		)
		(fp_line
			(start -0.67945 -0.3048)
			(end -0.67945 0.3048)
			(stroke
				(width 0.1)
				(type default)
			)
			(layer "B.Fab")
		)
		(fp_line
			(start -0.67945 0.3048)
			(end -0.120396 0.3048)
			(stroke
				(width 0.1)
				(type default)
			)
			(layer "B.Fab")
		)
		(fp_line
			(start -0.12065 -0.3048)
			(end -0.67945 -0.3048)
			(stroke
				(width 0.1)
				(type default)
			)
			(layer "B.Fab")
		)
		(fp_line
			(start -0.12065 -0.2794)
			(end -0.12065 -0.3048)
			(stroke
				(width 0.1)
				(type default)
			)
			(layer "B.Fab")
		)
		(fp_line
			(start -0.120396 0.2794)
			(end 0.12065 0.2794)
			(stroke
				(width 0.1)
				(type default)
			)
			(layer "B.Fab")
		)
		(fp_line
			(start -0.120396 0.3048)
			(end -0.120396 0.2794)
			(stroke
				(width 0.1)
				(type default)
			)
			(layer "B.Fab")
		)
		(fp_line
			(start 0.12065 -0.305054)
			(end 0.12065 -0.2794)
			(stroke
				(width 0.1)
				(type default)
			)
			(layer "B.Fab")
		)
		(fp_line
			(start 0.12065 -0.2794)
			(end -0.12065 -0.2794)
			(stroke
				(width 0.1)
				(type default)
			)
			(layer "B.Fab")
		)
		(fp_line
			(start 0.12065 0.2794)
			(end 0.12065 0.3048)
			(stroke
				(width 0.1)
				(type default)
			)
			(layer "B.Fab")
		)
		(fp_line
			(start 0.12065 0.3048)
			(end 0.67945 0.3048)
			(stroke
				(width 0.1)
				(type default)
			)
			(layer "B.Fab")
		)
		(fp_line
			(start 0.67945 -0.305054)
			(end 0.12065 -0.305054)
			(stroke
				(width 0.1)
				(type default)
			)
			(layer "B.Fab")
		)
		(fp_line
			(start 0.67945 0.3048)
			(end 0.67945 -0.305054)
			(stroke
				(width 0.1)
				(type default)
			)
			(layer "B.Fab")
		)
		(pad "1" smd circle
			(at 0.40005 0 180)
			(size 0 0)
			(layers "B.Cu" "B.Mask" "B.Paste")
			(net "P3V3_AUX")
		)
		(pad "2" smd circle
			(at -0.40005 0 180)
			(size 0 0)
			(layers "B.Cu" "B.Mask" "B.Paste")
			(net "FM_ADR_MODE1")
		)
	)
	(footprint ""
		(layer "B.Cu")
		(at 197.225158 -77.192632)
		(property "Reference" "U67"
			(at 2.032 -3.27533 0)
			(unlocked yes)
			(layer "B.SilkS")
			(effects
				(font
					(size 0.7874 0.5842)
					(thickness 0.1524)
				)
				(justify left mirror)
			)
		)
		(property "Value" ""
			(at 0 0 0)
			(layer "B.Fab")
			(effects
				(font
					(size 1.27 1.27)
				)
				(justify mirror)
			)
		)
		(duplicate_pad_numbers_are_jumpers no)
		(fp_line
			(start -2.0066 -2.5527)
			(end -2.0066 2.5527)
			(stroke
				(width 0.1524)
				(type default)
			)
			(layer "B.SilkS")
		)
		(fp_line
			(start -2.0066 2.5527)
			(end 2.0066 2.5527)
			(stroke
				(width 0.1524)
				(type default)
			)
			(layer "B.SilkS")
		)
		(fp_line
			(start -0.5715 -2.5527)
			(end -2.0066 -2.5527)
			(stroke
				(width 0.1524)
				(type default)
			)
			(layer "B.SilkS")
		)
		(fp_line
			(start 0 -1.9812)
			(end -0.5715 -2.5527)
			(stroke
				(width 0.1524)
				(type default)
			)
			(layer "B.SilkS")
		)
		(fp_line
			(start 0.5715 -2.5527)
			(end 0 -1.9812)
			(stroke
				(width 0.1524)
				(type default)
			)
			(layer "B.SilkS")
		)
		(fp_line
			(start 2.0066 -2.5527)
			(end 0.5715 -2.5527)
			(stroke
				(width 0.1524)
				(type default)
			)
			(layer "B.SilkS")
		)
		(fp_line
			(start 2.0066 2.5527)
			(end 2.0066 -2.5527)
			(stroke
				(width 0.1524)
				(type default)
			)
			(layer "B.SilkS")
		)
		(fp_poly
			(pts
				(xy 3.81 -1.905) (xy 4.36372 -2.233168) (xy 4.36372 -1.608328)
			)
			(stroke
				(width 0)
				(type default)
			)
			(fill yes)
			(layer "B.SilkS")
		)
		(fp_line
			(start -2.249932 -2.549906)
			(end -2.249932 2.549906)
			(stroke
				(width 0.1)
				(type default)
			)
			(layer "B.Fab")
		)
		(fp_line
			(start -2.249932 2.549906)
			(end 2.249932 2.549906)
			(stroke
				(width 0.1)
				(type default)
			)
			(layer "B.Fab")
		)
		(fp_line
			(start 2.249932 -2.549906)
			(end -2.249932 -2.549906)
			(stroke
				(width 0.1)
				(type default)
			)
			(layer "B.Fab")
		)
		(fp_line
			(start 2.249932 2.549906)
			(end 2.249932 -2.549906)
			(stroke
				(width 0.1)
				(type default)
			)
			(layer "B.Fab")
		)
		(fp_poly
			(pts
				(xy 4.36372 -1.608328) (xy 4.36372 -2.233168) (xy 3.81 -1.905)
			)
			(stroke
				(width 0)
				(type default)
			)
			(fill yes)
			(layer "B.Fab")
		)
		(pad "1" smd rect
			(at 2.921 -1.949958 270)
			(size 0.3556 1.4986)
			(layers "B.Cu" "B.Mask" "B.Paste")
			(net "FB_BMC_ISOLATE")
		)
		(pad "2" smd rect
			(at 2.921 -1.299972 270)
			(size 0.3556 1.4986)
			(layers "B.Cu" "B.Mask" "B.Paste")
			(net "NCSI_BMC_RXD1_R")
		)
		(pad "3" smd rect
			(at 2.921 -0.649986 270)
			(size 0.3556 1.4986)
			(layers "B.Cu" "B.Mask" "B.Paste")
			(net "NCSI_OCP_SFF_RXD1")
		)
		(pad "4" smd rect
			(at 2.921 0 270)
			(size 0.3556 1.4986)
			(layers "B.Cu" "B.Mask" "B.Paste")
			(net "FB_BMC_ISOLATE")
		)
		(pad "5" smd rect
			(at 2.921 0.649986 270)
			(size 0.3556 1.4986)
			(layers "B.Cu" "B.Mask" "B.Paste")
			(net "NCSI_BMC_RXD0_R")
		)
		(pad "6" smd rect
			(at 2.921 1.299972 270)
			(size 0.3556 1.4986)
			(layers "B.Cu" "B.Mask" "B.Paste")
			(net "NCSI_OCP_SFF_RXD0")
		)
		(pad "7" smd rect
			(at 2.921 1.949958 270)
			(size 0.3556 1.4986)
			(layers "B.Cu" "B.Mask" "B.Paste")
			(net "GND")
		)
		(pad "8" smd rect
			(at -2.921 1.949958 270)
			(size 0.3556 1.4986)
			(layers "B.Cu" "B.Mask" "B.Paste")
			(net "NCSI_OCP_SFF_CRS_DV")
		)
		(pad "9" smd rect
			(at -2.921 1.299972 270)
			(size 0.3556 1.4986)
			(layers "B.Cu" "B.Mask" "B.Paste")
			(net "NCSI_BMC_CRS_DV_R")
		)
		(pad "10" smd rect
			(at -2.921 0.649986 270)
			(size 0.3556 1.4986)
			(layers "B.Cu" "B.Mask" "B.Paste")
			(net "FB_BMC_ISOLATE")
		)
		(pad "11" smd rect
			(at -2.921 0 270)
			(size 0.3556 1.4986)
			(layers "B.Cu" "B.Mask" "B.Paste")
			(net "OCP_SFF_ISO1_RBT_ARB_IN")
		)
		(pad "12" smd rect
			(at -2.921 -0.649986 270)
			(size 0.3556 1.4986)
			(layers "B.Cu" "B.Mask" "B.Paste")
			(net "OCP_SFF_RBT_ARB_IN_R")
		)
		(pad "13" smd rect
			(at -2.921 -1.299972 270)
			(size 0.3556 1.4986)
			(layers "B.Cu" "B.Mask" "B.Paste")
			(net "FB_BMC_ISOLATE")
		)
		(pad "14" smd rect
			(at -2.921 -1.949958 270)
			(size 0.3556 1.4986)
			(layers "B.Cu" "B.Mask" "B.Paste")
			(net "P3V3_AUX")
		)
	)
	(footprint ""
		(layer "B.Cu")
		(at 349.344742 -210.41868 180)
		(property "Reference" "C516"
			(at 0 0 0)
			(layer "B.SilkS")
			(hide yes)
			(effects
				(font
					(size 1.27 1.27)
				)
				(justify mirror)
			)
		)
		(property "Value" ""
			(at 0 0 0)
			(layer "B.Fab")
			(effects
				(font
					(size 1.27 1.27)
				)
				(justify mirror)
			)
		)
		(duplicate_pad_numbers_are_jumpers no)
		(fp_line
			(start 1.2954 0.5842)
			(end 1.2954 -0.5842)
			(stroke
				(width 0.1524)
				(type default)
			)
			(layer "B.SilkS")
		)
		(fp_line
			(start 1.2954 -0.5842)
			(end -1.2954 -0.5842)
			(stroke
				(width 0.1524)
				(type default)
			)
			(layer "B.SilkS")
		)
		(fp_line
			(start 0 -0.5842)
			(end 0 0.5842)
			(stroke
				(width 0.1524)
				(type default)
			)
			(layer "B.SilkS")
		)
		(fp_line
			(start -1.2954 0.5842)
			(end 1.2954 0.5842)
			(stroke
				(width 0.1524)
				(type default)
			)
			(layer "B.SilkS")
		)
		(fp_line
			(start -1.2954 -0.5842)
			(end -1.2954 0.5842)
			(stroke
				(width 0.1524)
				(type default)
			)
			(layer "B.SilkS")
		)
		(fp_line
			(start 1.1938 0.4064)
			(end 1.1938 -0.4064)
			(stroke
				(width 0.1)
				(type default)
			)
			(layer "B.Fab")
		)
		(fp_line
			(start 1.1938 -0.4064)
			(end 0.8636 -0.4064)
			(stroke
				(width 0.1)
				(type default)
			)
			(layer "B.Fab")
		)
		(fp_line
			(start 0.8636 0.4572)
			(end 0.8636 0.4064)
			(stroke
				(width 0.1)
				(type default)
			)
			(layer "B.Fab")
		)
		(fp_line
			(start 0.8636 0.4064)
			(end 1.1938 0.4064)
			(stroke
				(width 0.1)
				(type default)
			)
			(layer "B.Fab")
		)
		(fp_line
			(start 0.8636 -0.4064)
			(end 0.8636 -0.4572)
			(stroke
				(width 0.1)
				(type default)
			)
			(layer "B.Fab")
		)
		(fp_line
			(start 0.8636 -0.4572)
			(end -0.8636 -0.4572)
			(stroke
				(width 0.1)
				(type default)
			)
			(layer "B.Fab")
		)
		(fp_line
			(start -0.8636 0.4572)
			(end 0.8636 0.4572)
			(stroke
				(width 0.1)
				(type default)
			)
			(layer "B.Fab")
		)
		(fp_line
			(start -0.8636 0.4064)
			(end -0.8636 0.4572)
			(stroke
				(width 0.1)
				(type default)
			)
			(layer "B.Fab")
		)
		(fp_line
			(start -0.8636 -0.4064)
			(end -1.1938 -0.4064)
			(stroke
				(width 0.1)
				(type default)
			)
			(layer "B.Fab")
		)
		(fp_line
			(start -0.8636 -0.4572)
			(end -0.8636 -0.4064)
			(stroke
				(width 0.1)
				(type default)
			)
			(layer "B.Fab")
		)
		(fp_line
			(start -1.1938 0.4064)
			(end -0.8636 0.4064)
			(stroke
				(width 0.1)
				(type default)
			)
			(layer "B.Fab")
		)
		(fp_line
			(start -1.1938 -0.4064)
			(end -1.1938 0.4064)
			(stroke
				(width 0.1)
				(type default)
			)
			(layer "B.Fab")
		)
		(pad "1" smd rect
			(at 0.7366 0 90)
			(size 0.7112 0.8128)
			(layers "B.Cu" "B.Mask" "B.Paste")
			(net "PVCCFA_EHV_CPU0")
		)
		(pad "2" smd rect
			(at -0.7366 0 90)
			(size 0.7112 0.8128)
			(layers "B.Cu" "B.Mask" "B.Paste")
			(net "GND")
		)
	)
	(footprint ""
		(layer "B.Cu")
		(at 143.793718 -335.62798)
		(property "Reference" "C1390"
			(at 0 0 0)
			(layer "B.SilkS")
			(hide yes)
			(effects
				(font
					(size 1.27 1.27)
				)
				(justify mirror)
			)
		)
		(property "Value" ""
			(at 0 0 0)
			(layer "B.Fab")
			(effects
				(font
					(size 1.27 1.27)
				)
				(justify mirror)
			)
		)
		(duplicate_pad_numbers_are_jumpers no)
		(fp_line
			(start -1.524 -0.762)
			(end -1.524 0.762)
			(stroke
				(width 0.1524)
				(type default)
			)
			(layer "B.SilkS")
		)
		(fp_line
			(start -1.524 0.762)
			(end 1.524 0.762)
			(stroke
				(width 0.1524)
				(type default)
			)
			(layer "B.SilkS")
		)
		(fp_line
			(start 1.524 -0.762)
			(end -1.524 -0.762)
			(stroke
				(width 0.1524)
				(type default)
			)
			(layer "B.SilkS")
		)
		(fp_line
			(start 1.524 0.762)
			(end 1.524 -0.762)
			(stroke
				(width 0.1524)
				(type default)
			)
			(layer "B.SilkS")
		)
		(fp_line
			(start -1.1049 -0.724916)
			(end 1.1049 -0.724916)
			(stroke
				(width 0.1)
				(type default)
			)
			(layer "B.Fab")
		)
		(fp_line
			(start -1.1049 0.724916)
			(end -1.1049 -0.724916)
			(stroke
				(width 0.1)
				(type default)
			)
			(layer "B.Fab")
		)
		(fp_line
			(start 1.1049 -0.724916)
			(end 1.1049 0.724916)
			(stroke
				(width 0.1)
				(type default)
			)
			(layer "B.Fab")
		)
		(fp_line
			(start 1.1049 0.724916)
			(end -1.1049 0.724916)
			(stroke
				(width 0.1)
				(type default)
			)
			(layer "B.Fab")
		)
		(pad "1" smd rect
			(at 0.889 0)
			(size 1.016 1.27)
			(layers "B.Cu" "B.Mask" "B.Paste")
			(net "PVPP_HBM_CPU1")
		)
		(pad "2" smd rect
			(at -0.889 0)
			(size 1.016 1.27)
			(layers "B.Cu" "B.Mask" "B.Paste")
			(net "GND")
		)
	)
)
